# T6G (Grand Teton) — schematic netlist excerpt (pin names and nets, part order shuffled) for the footprints in the layout excerpt that follows; sources: Cadence DE-HDL packaged netlist, KiCad conversion of 04192023_DAF0TMB3IC0_F0TG_MB_C_brd_V02_OCP.brd

PC153_2  Q_CAP  22UF 16V 20% X6S  pkg C0805  page 205 : A = SW_P12V_AUX_PVDDIO_P0_FLT ; B = GND
PC344_1  Q_CAP  22UF 4V 20% X6S  pkg C0805  page 215 : A = PVDDCR_SOC_P1 ; B = GND
R712  Q_RES  0 5% CHIP  pkg 0603LF  page 334 : A = P0V9_CPU1_RT1_2A_2D ; B = P0V9_CPU1_RT1_2A
C135  Q_CAP  1UF 4V 20% X6S  pkg 0201  page 323 : A = P0V9_CPU1_RT0_2A ; B = GND

(kicad_pcb
	(version 20260206)
	(generator "pcbnew")
	(generator_version "10.0")
	(general
		(thickness 1.6)
		(legacy_teardrops no)
	)
	(paper "A4")
	(title_block
		(title "04192023_DAF0TMB3IC0_F0TG_MB_C_brd_V02_OCP.brd")
		(comment 1 "Grand Teton / footprints 6931-6934 of 8354")
	)
	(layers
		(0 "F.Cu" signal "TOP")
		(4 "In1.Cu" signal "GND")
		(6 "In2.Cu" signal "IN1")
		(8 "In3.Cu" signal "GND1")
		(10 "In4.Cu" signal "IN2")
		(12 "In5.Cu" signal "GND2")
		(14 "In6.Cu" signal "IN3")
		(16 "In7.Cu" signal "GND3")
		(18 "In8.Cu" signal "VCC")
		(20 "In9.Cu" signal "VCC1")
		(22 "In10.Cu" signal "GND4")
		(24 "In11.Cu" signal "IN4")
		(26 "In12.Cu" signal "GND5")
		(28 "In13.Cu" signal "IN5")
		(30 "In14.Cu" signal "GND6")
		(32 "In15.Cu" signal "IN6")
		(34 "In16.Cu" signal "GND7")
		(2 "B.Cu" signal "BOTTOM")
		(9 "F.Adhes" user "F.Adhesive")
		(11 "B.Adhes" user "B.Adhesive")
		(13 "F.Paste" user "Package Geometry/Pastemask Top")
		(15 "B.Paste" user "Package Geometry/Pastemask Bottom")
		(5 "F.SilkS" user "Ref Des/Silkscreen Top")
		(7 "B.SilkS" user "Ref Des/Silkscreen Bottom")
		(1 "F.Mask" user "Board Geometry/Soldermask Top")
		(3 "B.Mask" user "Board Geometry/Soldermask Bottom")
		(17 "Dwgs.User" user "User.Drawings")
		(19 "Cmts.User" user "User.Comments")
		(21 "Eco1.User" user "User.Eco1")
		(23 "Eco2.User" user "User.Eco2")
		(25 "Edge.Cuts" user "Board Geometry/Outline")
		(27 "Margin" user)
		(31 "F.CrtYd" user "Package Geometry/Place Bound Top")
		(29 "B.CrtYd" user "Package Geometry/Place Bound Bottom")
		(35 "F.Fab" user "Ref Des/Assembly Top")
		(33 "B.Fab" user "Ref Des/Assembly Bottom")
	)
	(footprint ""
		(layer "B.Cu")
		(at 47.37862 -386.766562 90)
		(property "Reference" "C135"
			(at 0 0 90)
			(layer "B.SilkS")
			(hide yes)
			(effects
				(font
					(size 1.27 1.27)
				)
				(justify mirror)
			)
		)
		(property "Value" ""
			(at 0 0 90)
			(layer "B.Fab")
			(effects
				(font
					(size 1.27 1.27)
				)
				(justify mirror)
			)
		)
		(duplicate_pad_numbers_are_jumpers no)
		(fp_line
			(start 0.299974 -0.150114)
			(end -0.299974 -0.150114)
			(stroke
				(width 0.1)
				(type default)
			)
			(layer "B.Fab")
		)
		(fp_line
			(start -0.299974 -0.150114)
			(end -0.299974 0.150114)
			(stroke
				(width 0.1)
				(type default)
			)
			(layer "B.Fab")
		)
		(fp_line
			(start 0.299974 0.150114)
			(end 0.299974 -0.150114)
			(stroke
				(width 0.1)
				(type default)
			)
			(layer "B.Fab")
		)
		(fp_line
			(start -0.299974 0.150114)
			(end 0.299974 0.150114)
			(stroke
				(width 0.1)
				(type default)
			)
			(layer "B.Fab")
		)
		(pad "1" smd rect
			(at 0.2667 0 270)
			(size 0.3048 0.381)
			(layers "B.Cu" "B.Mask" "B.Paste")
			(net "P0V9_CPU1_RT0_2A")
		)
		(pad "2" smd rect
			(at -0.2667 0 270)
			(size 0.3048 0.381)
			(layers "B.Cu" "B.Mask" "B.Paste")
			(net "GND")
		)
	)
	(footprint ""
		(layer "B.Cu")
		(at 73.889616 -393.242546 180)
		(property "Reference" "R712"
			(at 0 0 0)
			(layer "B.SilkS")
			(hide yes)
			(effects
				(font
					(size 1.27 1.27)
				)
				(justify mirror)
			)
		)
		(property "Value" ""
			(at 0 0 0)
			(layer "B.Fab")
			(effects
				(font
					(size 1.27 1.27)
				)
				(justify mirror)
			)
		)
		(duplicate_pad_numbers_are_jumpers no)
		(fp_line
			(start 1.2954 0.5842)
			(end 1.2954 -0.5842)
			(stroke
				(width 0.1524)
				(type default)
			)
			(layer "B.SilkS")
		)
		(fp_line
			(start 1.2954 -0.5842)
			(end -1.2954 -0.5842)
			(stroke
				(width 0.1524)
				(type default)
			)
			(layer "B.SilkS")
		)
		(fp_line
			(start -1.2954 0.5842)
			(end 1.2954 0.5842)
			(stroke
				(width 0.1524)
				(type default)
			)
			(layer "B.SilkS")
		)
		(fp_line
			(start -1.2954 -0.5842)
			(end -1.2954 0.5842)
			(stroke
				(width 0.1524)
				(type default)
			)
			(layer "B.SilkS")
		)
		(fp_line
			(start 1.1938 0.4064)
			(end 1.1938 -0.406654)
			(stroke
				(width 0.1)
				(type default)
			)
			(layer "B.Fab")
		)
		(fp_line
			(start 1.1938 -0.406654)
			(end 0.8636 -0.406654)
			(stroke
				(width 0.1)
				(type default)
			)
			(layer "B.Fab")
		)
		(fp_line
			(start 0.8636 0.4572)
			(end 0.8636 0.4318)
			(stroke
				(width 0.1)
				(type default)
			)
			(layer "B.Fab")
		)
		(fp_line
			(start 0.8636 0.4318)
			(end 0.8636 0.4064)
			(stroke
				(width 0.1)
				(type default)
			)
			(layer "B.Fab")
		)
		(fp_line
			(start 0.8636 0.4064)
			(end 1.1938 0.4064)
			(stroke
				(width 0.1)
				(type default)
			)
			(layer "B.Fab")
		)
		(fp_line
			(start 0.8636 -0.406654)
			(end 0.8636 -0.4572)
			(stroke
				(width 0.1)
				(type default)
			)
			(layer "B.Fab")
		)
		(fp_line
			(start 0.8636 -0.4572)
			(end -0.8636 -0.4572)
			(stroke
				(width 0.1)
				(type default)
			)
			(layer "B.Fab")
		)
		(fp_line
			(start -0.8636 0.4572)
			(end 0.8636 0.4572)
			(stroke
				(width 0.1)
				(type default)
			)
			(layer "B.Fab")
		)
		(fp_line
			(start -0.8636 0.4064)
			(end -0.8636 0.4572)
			(stroke
				(width 0.1)
				(type default)
			)
			(layer "B.Fab")
		)
		(fp_line
			(start -0.8636 -0.406654)
			(end -1.1938 -0.406654)
			(stroke
				(width 0.1)
				(type default)
			)
			(layer "B.Fab")
		)
		(fp_line
			(start -0.8636 -0.4572)
			(end -0.8636 -0.406654)
			(stroke
				(width 0.1)
				(type default)
			)
			(layer "B.Fab")
		)
		(fp_line
			(start -1.1938 0.4064)
			(end -0.8636 0.4064)
			(stroke
				(width 0.1)
				(type default)
			)
			(layer "B.Fab")
		)
		(fp_line
			(start -1.1938 -0.406654)
			(end -1.1938 0.4064)
			(stroke
				(width 0.1)
				(type default)
			)
			(layer "B.Fab")
		)
		(pad "1" smd rect
			(at 0.7366 0 90)
			(size 0.7112 0.8128)
			(layers "B.Cu" "B.Mask" "B.Paste")
			(net "P0V9_CPU1_RT1_2A_2D")
		)
		(pad "2" smd rect
			(at -0.7366 0 90)
			(size 0.7112 0.8128)
			(layers "B.Cu" "B.Mask" "B.Paste")
			(net "P0V9_CPU1_RT1_2A")
		)
	)
	(footprint ""
		(layer "B.Cu")
		(at 293.12997 -346.784168 90)
		(property "Reference" "PC153_2"
			(at 0 0 90)
			(layer "B.SilkS")
			(hide yes)
			(effects
				(font
					(size 1.27 1.27)
				)
				(justify mirror)
			)
		)
		(property "Value" ""
			(at 0 0 90)
			(layer "B.Fab")
			(effects
				(font
					(size 1.27 1.27)
				)
				(justify mirror)
			)
		)
		(duplicate_pad_numbers_are_jumpers no)
		(fp_line
			(start 1.524 -0.762)
			(end -1.524 -0.762)
			(stroke
				(width 0.1524)
				(type default)
			)
			(layer "B.SilkS")
		)
		(fp_line
			(start -1.524 -0.762)
			(end -1.524 0.762)
			(stroke
				(width 0.1524)
				(type default)
			)
			(layer "B.SilkS")
		)
		(fp_line
			(start 1.524 0.762)
			(end 1.524 -0.762)
			(stroke
				(width 0.1524)
				(type default)
			)
			(layer "B.SilkS")
		)
		(fp_line
			(start -1.524 0.762)
			(end 1.524 0.762)
			(stroke
				(width 0.1524)
				(type default)
			)
			(layer "B.SilkS")
		)
		(fp_line
			(start 1.1049 -0.724916)
			(end 1.1049 0.724916)
			(stroke
				(width 0.1)
				(type default)
			)
			(layer "B.Fab")
		)
		(fp_line
			(start -1.1049 -0.724916)
			(end 1.1049 -0.724916)
			(stroke
				(width 0.1)
				(type default)
			)
			(layer "B.Fab")
		)
		(fp_line
			(start 1.1049 0.724916)
			(end -1.1049 0.724916)
			(stroke
				(width 0.1)
				(type default)
			)
			(layer "B.Fab")
		)
		(fp_line
			(start -1.1049 0.724916)
			(end -1.1049 -0.724916)
			(stroke
				(width 0.1)
				(type default)
			)
			(layer "B.Fab")
		)
		(pad "1" smd rect
			(at 0.889 0 90)
			(size 1.016 1.27)
			(layers "B.Cu" "B.Mask" "B.Paste")
			(net "SW_P12V_AUX_PVDDIO_P0_FLT")
		)
		(pad "2" smd rect
			(at -0.889 0 90)
			(size 1.016 1.27)
			(layers "B.Cu" "B.Mask" "B.Paste")
			(net "GND")
		)
	)
	(footprint ""
		(layer "B.Cu")
		(at 119.621554 -177.007012 90)
		(property "Reference" "PC344_1"
			(at 0 0 90)
			(layer "B.SilkS")
			(hide yes)
			(effects
				(font
					(size 1.27 1.27)
				)
				(justify mirror)
			)
		)
		(property "Value" ""
			(at 0 0 90)
			(layer "B.Fab")
			(effects
				(font
					(size 1.27 1.27)
				)
				(justify mirror)
			)
		)
		(duplicate_pad_numbers_are_jumpers no)
		(fp_line
			(start 1.524 -0.762)
			(end -1.524 -0.762)
			(stroke
				(width 0.1524)
				(type default)
			)
			(layer "B.SilkS")
		)
		(fp_line
			(start -1.524 -0.762)
			(end -1.524 0.762)
			(stroke
				(width 0.1524)
				(type default)
			)
			(layer "B.SilkS")
		)
		(fp_line
			(start 1.524 0.762)
			(end 1.524 -0.762)
			(stroke
				(width 0.1524)
				(type default)
			)
			(layer "B.SilkS")
		)
		(fp_line
			(start -1.524 0.762)
			(end 1.524 0.762)
			(stroke
				(width 0.1524)
				(type default)
			)
			(layer "B.SilkS")
		)
		(fp_line
			(start 1.1049 -0.724916)
			(end 1.1049 0.724916)
			(stroke
				(width 0.1)
				(type default)
			)
			(layer "B.Fab")
		)
		(fp_line
			(start -1.1049 -0.724916)
			(end 1.1049 -0.724916)
			(stroke
				(width 0.1)
				(type default)
			)
			(layer "B.Fab")
		)
		(fp_line
			(start 1.1049 0.724916)
			(end -1.1049 0.724916)
			(stroke
				(width 0.1)
				(type default)
			)
			(layer "B.Fab")
		)
		(fp_line
			(start -1.1049 0.724916)
			(end -1.1049 -0.724916)
			(stroke
				(width 0.1)
				(type default)
			)
			(layer "B.Fab")
		)
		(pad "1" smd rect
			(at 0.889 0 90)
			(size 1.016 1.27)
			(layers "B.Cu" "B.Mask" "B.Paste")
			(net "PVDDCR_SOC_P1")
		)
		(pad "2" smd rect
			(at -0.889 0 90)
			(size 1.016 1.27)
			(layers "B.Cu" "B.Mask" "B.Paste")
			(net "GND")
		)
	)
)
